(kicad_pcb
	(version 20260206)
	(generator "pcbnew")
	(generator_version "10.0")
	(general
		(thickness 1.6)
		(legacy_teardrops no)
	)
	(paper "A4")
	(title_block
		(title "04192023_DAF0TMB3IC0_F0TG_MB_C_brd_V02_OCP.brd")
		(comment 1 "Grand Teton / footprints 4625-4630 of 8354")
	)
	(layers
		(0 "F.Cu" signal "TOP")
		(4 "In1.Cu" signal "GND")
		(6 "In2.Cu" signal "IN1")
		(8 "In3.Cu" signal "GND1")
		(10 "In4.Cu" signal "IN2")
		(12 "In5.Cu" signal "GND2")
		(14 "In6.Cu" signal "IN3")
		(16 "In7.Cu" signal "GND3")
		(18 "In8.Cu" signal "VCC")
		(20 "In9.Cu" signal "VCC1")
		(22 "In10.Cu" signal "GND4")
		(24 "In11.Cu" signal "IN4")
		(26 "In12.Cu" signal "GND5")
		(28 "In13.Cu" signal "IN5")
		(30 "In14.Cu" signal "GND6")
		(32 "In15.Cu" signal "IN6")
		(34 "In16.Cu" signal "GND7")
		(2 "B.Cu" signal "BOTTOM")
		(9 "F.Adhes" user "F.Adhesive")
		(11 "B.Adhes" user "B.Adhesive")
		(13 "F.Paste" user "Package Geometry/Pastemask Top")
		(15 "B.Paste" user "Package Geometry/Pastemask Bottom")
		(5 "F.SilkS" user "Ref Des/Silkscreen Top")
		(7 "B.SilkS" user "Ref Des/Silkscreen Bottom")
		(1 "F.Mask" user "Board Geometry/Soldermask Top")
		(3 "B.Mask" user "Board Geometry/Soldermask Bottom")
		(17 "Dwgs.User" user "User.Drawings")
		(19 "Cmts.User" user "User.Comments")
		(21 "Eco1.User" user "User.Eco1")
		(23 "Eco2.User" user "User.Eco2")
		(25 "Edge.Cuts" user "Board Geometry/Outline")
		(27 "Margin" user)
		(31 "F.CrtYd" user "Package Geometry/Place Bound Top")
		(29 "B.CrtYd" user "Package Geometry/Place Bound Bottom")
		(35 "F.Fab" user "Ref Des/Assembly Top")
		(33 "B.Fab" user "Ref Des/Assembly Bottom")
	)
	(footprint ""
		(layer "F.Cu")
		(at 335.264252 -357.703628 180)
		(property "Reference" "PC85"
			(at 0 0 180)
			(layer "F.SilkS")
			(hide yes)
			(effects
				(font
					(size 1.27 1.27)
				)
			)
		)
		(property "Value" ""
			(at 0 0 180)
			(layer "F.Fab")
			(effects
				(font
					(size 1.27 1.27)
				)
			)
		)
		(duplicate_pad_numbers_are_jumpers no)
		(fp_line
			(start 0.7874 0.4064)
			(end -0.7874 0.4064)
			(stroke
				(width 0.1524)
				(type default)
			)
			(layer "F.SilkS")
		)
		(fp_line
			(start 0.7874 -0.4064)
			(end 0.7874 0.4064)
			(stroke
				(width 0.1524)
				(type default)
			)
			(layer "F.SilkS")
		)
		(fp_line
			(start -0.7874 0.4064)
			(end -0.7874 -0.4064)
			(stroke
				(width 0.1524)
				(type default)
			)
			(layer "F.SilkS")
		)
		(fp_line
			(start -0.7874 -0.4064)
			(end 0.7874 -0.4064)
			(stroke
				(width 0.1524)
				(type default)
			)
			(layer "F.SilkS")
		)
		(fp_line
			(start 0.67945 0.3048)
			(end 0.120396 0.3048)
			(stroke
				(width 0.1)
				(type default)
			)
			(layer "F.Fab")
		)
		(fp_line
			(start 0.67945 -0.3048)
			(end 0.67945 0.3048)
			(stroke
				(width 0.1)
				(type default)
			)
			(layer "F.Fab")
		)
		(fp_line
			(start 0.12065 -0.2794)
			(end 0.12065 -0.3048)
			(stroke
				(width 0.1)
				(type default)
			)
			(layer "F.Fab")
		)
		(fp_line
			(start 0.12065 -0.3048)
			(end 0.67945 -0.3048)
			(stroke
				(width 0.1)
				(type default)
			)
			(layer "F.Fab")
		)
		(fp_line
			(start 0.120396 0.3048)
			(end 0.120396 0.2794)
			(stroke
				(width 0.1)
				(type default)
			)
			(layer "F.Fab")
		)
		(fp_line
			(start 0.120396 0.2794)
			(end -0.12065 0.2794)
			(stroke
				(width 0.1)
				(type default)
			)
			(layer "F.Fab")
		)
		(fp_line
			(start -0.12065 0.3048)
			(end -0.67945 0.3048)
			(stroke
				(width 0.1)
				(type default)
			)
			(layer "F.Fab")
		)
		(fp_line
			(start -0.12065 0.2794)
			(end -0.12065 0.3048)
			(stroke
				(width 0.1)
				(type default)
			)
			(layer "F.Fab")
		)
		(fp_line
			(start -0.12065 -0.2794)
			(end 0.12065 -0.2794)
			(stroke
				(width 0.1)
				(type default)
			)
			(layer "F.Fab")
		)
		(fp_line
			(start -0.12065 -0.305054)
			(end -0.12065 -0.2794)
			(stroke
				(width 0.1)
				(type default)
			)
			(layer "F.Fab")
		)
		(fp_line
			(start -0.67945 0.3048)
			(end -0.67945 -0.305054)
			(stroke
				(width 0.1)
				(type default)
			)
			(layer "F.Fab")
		)
		(fp_line
			(start -0.67945 -0.305054)
			(end -0.12065 -0.305054)
			(stroke
				(width 0.1)
				(type default)
			)
			(layer "F.Fab")
		)
		(pad "1" smd circle
			(at -0.40005 0 180)
			(size 0 0)
			(layers "F.Cu" "F.Mask" "F.Paste")
			(net "P12V_AUX")
		)
		(pad "2" smd circle
			(at 0.40005 0 180)
			(size 0 0)
			(layers "F.Cu" "F.Mask" "F.Paste")
			(net "GND")
		)
	)
	(footprint ""
		(layer "F.Cu")
		(at 208.894426 -110.649512 180)
		(property "Reference" "R2845"
			(at 0 0 180)
			(layer "F.SilkS")
			(hide yes)
			(effects
				(font
					(size 1.27 1.27)
				)
			)
		)
		(property "Value" ""
			(at 0 0 180)
			(layer "F.Fab")
			(effects
				(font
					(size 1.27 1.27)
				)
			)
		)
		(duplicate_pad_numbers_are_jumpers no)
		(fp_line
			(start 0.7874 0.4064)
			(end -0.7874 0.4064)
			(stroke
				(width 0.1524)
				(type default)
			)
			(layer "F.SilkS")
		)
		(fp_line
			(start 0.7874 -0.4064)
			(end 0.7874 0.4064)
			(stroke
				(width 0.1524)
				(type default)
			)
			(layer "F.SilkS")
		)
		(fp_line
			(start -0.7874 0.4064)
			(end -0.7874 -0.4064)
			(stroke
				(width 0.1524)
				(type default)
			)
			(layer "F.SilkS")
		)
		(fp_line
			(start -0.7874 -0.4064)
			(end 0.7874 -0.4064)
			(stroke
				(width 0.1524)
				(type default)
			)
			(layer "F.SilkS")
		)
		(fp_line
			(start 0.67945 0.3048)
			(end 0.120396 0.3048)
			(stroke
				(width 0.1)
				(type default)
			)
			(layer "F.Fab")
		)
		(fp_line
			(start 0.67945 -0.3048)
			(end 0.67945 0.3048)
			(stroke
				(width 0.1)
				(type default)
			)
			(layer "F.Fab")
		)
		(fp_line
			(start 0.12065 -0.2794)
			(end 0.12065 -0.3048)
			(stroke
				(width 0.1)
				(type default)
			)
			(layer "F.Fab")
		)
		(fp_line
			(start 0.12065 -0.3048)
			(end 0.67945 -0.3048)
			(stroke
				(width 0.1)
				(type default)
			)
			(layer "F.Fab")
		)
		(fp_line
			(start 0.120396 0.3048)
			(end 0.120396 0.2794)
			(stroke
				(width 0.1)
				(type default)
			)
			(layer "F.Fab")
		)
		(fp_line
			(start 0.120396 0.2794)
			(end -0.12065 0.2794)
			(stroke
				(width 0.1)
				(type default)
			)
			(layer "F.Fab")
		)
		(fp_line
			(start -0.12065 0.3048)
			(end -0.67945 0.3048)
			(stroke
				(width 0.1)
				(type default)
			)
			(layer "F.Fab")
		)
		(fp_line
			(start -0.12065 0.2794)
			(end -0.12065 0.3048)
			(stroke
				(width 0.1)
				(type default)
			)
			(layer "F.Fab")
		)
		(fp_line
			(start -0.12065 -0.2794)
			(end 0.12065 -0.2794)
			(stroke
				(width 0.1)
				(type default)
			)
			(layer "F.Fab")
		)
		(fp_line
			(start -0.12065 -0.305054)
			(end -0.12065 -0.2794)
			(stroke
				(width 0.1)
				(type default)
			)
			(layer "F.Fab")
		)
		(fp_line
			(start -0.67945 0.3048)
			(end -0.67945 -0.305054)
			(stroke
				(width 0.1)
				(type default)
			)
			(layer "F.Fab")
		)
		(fp_line
			(start -0.67945 -0.305054)
			(end -0.12065 -0.305054)
			(stroke
				(width 0.1)
				(type default)
			)
			(layer "F.Fab")
		)
		(pad "1" smd circle
			(at -0.40005 0 180)
			(size 0 0)
			(layers "F.Cu" "F.Mask" "F.Paste")
			(net "BMC_MONITER_R")
		)
		(pad "2" smd circle
			(at 0.40005 0 180)
			(size 0 0)
			(layers "F.Cu" "F.Mask" "F.Paste")
			(net "BMC_MONITER")
		)
	)
	(footprint ""
		(layer "F.Cu")
		(at 180.7718 -40.071548)
		(property "Reference" "R1396"
			(at 0 0 0)
			(layer "F.SilkS")
			(hide yes)
			(effects
				(font
					(size 1.27 1.27)
				)
			)
		)
		(property "Value" ""
			(at 0 0 0)
			(layer "F.Fab")
			(effects
				(font
					(size 1.27 1.27)
				)
			)
		)
		(duplicate_pad_numbers_are_jumpers no)
		(fp_line
			(start -0.7874 -0.4064)
			(end 0.7874 -0.4064)
			(stroke
				(width 0.1524)
				(type default)
			)
			(layer "F.SilkS")
		)
		(fp_line
			(start -0.7874 0.4064)
			(end -0.7874 -0.4064)
			(stroke
				(width 0.1524)
				(type default)
			)
			(layer "F.SilkS")
		)
		(fp_line
			(start 0.7874 -0.4064)
			(end 0.7874 0.4064)
			(stroke
				(width 0.1524)
				(type default)
			)
			(layer "F.SilkS")
		)
		(fp_line
			(start 0.7874 0.4064)
			(end -0.7874 0.4064)
			(stroke
				(width 0.1524)
				(type default)
			)
			(layer "F.SilkS")
		)
		(fp_line
			(start -0.67945 -0.305054)
			(end -0.12065 -0.305054)
			(stroke
				(width 0.1)
				(type default)
			)
			(layer "F.Fab")
		)
		(fp_line
			(start -0.67945 0.3048)
			(end -0.67945 -0.305054)
			(stroke
				(width 0.1)
				(type default)
			)
			(layer "F.Fab")
		)
		(fp_line
			(start -0.12065 -0.305054)
			(end -0.12065 -0.2794)
			(stroke
				(width 0.1)
				(type default)
			)
			(layer "F.Fab")
		)
		(fp_line
			(start -0.12065 -0.2794)
			(end 0.12065 -0.2794)
			(stroke
				(width 0.1)
				(type default)
			)
			(layer "F.Fab")
		)
		(fp_line
			(start -0.12065 0.2794)
			(end -0.12065 0.3048)
			(stroke
				(width 0.1)
				(type default)
			)
			(layer "F.Fab")
		)
		(fp_line
			(start -0.12065 0.3048)
			(end -0.67945 0.3048)
			(stroke
				(width 0.1)
				(type default)
			)
			(layer "F.Fab")
		)
		(fp_line
			(start 0.120396 0.2794)
			(end -0.12065 0.2794)
			(stroke
				(width 0.1)
				(type default)
			)
			(layer "F.Fab")
		)
		(fp_line
			(start 0.120396 0.3048)
			(end 0.120396 0.2794)
			(stroke
				(width 0.1)
				(type default)
			)
			(layer "F.Fab")
		)
		(fp_line
			(start 0.12065 -0.3048)
			(end 0.67945 -0.3048)
			(stroke
				(width 0.1)
				(type default)
			)
			(layer "F.Fab")
		)
		(fp_line
			(start 0.12065 -0.2794)
			(end 0.12065 -0.3048)
			(stroke
				(width 0.1)
				(type default)
			)
			(layer "F.Fab")
		)
		(fp_line
			(start 0.67945 -0.3048)
			(end 0.67945 0.3048)
			(stroke
				(width 0.1)
				(type default)
			)
			(layer "F.Fab")
		)
		(fp_line
			(start 0.67945 0.3048)
			(end 0.120396 0.3048)
			(stroke
				(width 0.1)
				(type default)
			)
			(layer "F.Fab")
		)
		(pad "1" smd circle
			(at -0.40005 0)
			(size 0 0)
			(layers "F.Cu" "F.Mask" "F.Paste")
			(net "FM_M2_SSD_0_PEDET")
		)
		(pad "2" smd circle
			(at 0.40005 0)
			(size 0 0)
			(layers "F.Cu" "F.Mask" "F.Paste")
			(net "P3V3_AUX")
		)
	)
	(footprint ""
		(layer "F.Cu")
		(at 48.19904 -434.057552 -90)
		(property "Reference" "R3315"
			(at 0 0 270)
			(layer "F.SilkS")
			(hide yes)
			(effects
				(font
					(size 1.27 1.27)
				)
			)
		)
		(property "Value" ""
			(at 0 0 270)
			(layer "F.Fab")
			(effects
				(font
					(size 1.27 1.27)
				)
			)
		)
		(duplicate_pad_numbers_are_jumpers no)
		(fp_line
			(start -0.7874 0.4064)
			(end -0.7874 -0.4064)
			(stroke
				(width 0.1524)
				(type default)
			)
			(layer "F.SilkS")
		)
		(fp_line
			(start 0.7874 0.4064)
			(end -0.7874 0.4064)
			(stroke
				(width 0.1524)
				(type default)
			)
			(layer "F.SilkS")
		)
		(fp_line
			(start -0.7874 -0.4064)
			(end 0.7874 -0.4064)
			(stroke
				(width 0.1524)
				(type default)
			)
			(layer "F.SilkS")
		)
		(fp_line
			(start 0.7874 -0.4064)
			(end 0.7874 0.4064)
			(stroke
				(width 0.1524)
				(type default)
			)
			(layer "F.SilkS")
		)
		(fp_line
			(start -0.67945 0.3048)
			(end -0.67945 -0.305054)
			(stroke
				(width 0.1)
				(type default)
			)
			(layer "F.Fab")
		)
		(fp_line
			(start -0.12065 0.3048)
			(end -0.67945 0.3048)
			(stroke
				(width 0.1)
				(type default)
			)
			(layer "F.Fab")
		)
		(fp_line
			(start 0.120396 0.3048)
			(end 0.120396 0.2794)
			(stroke
				(width 0.1)
				(type default)
			)
			(layer "F.Fab")
		)
		(fp_line
			(start 0.67945 0.3048)
			(end 0.120396 0.3048)
			(stroke
				(width 0.1)
				(type default)
			)
			(layer "F.Fab")
		)
		(fp_line
			(start -0.12065 0.2794)
			(end -0.12065 0.3048)
			(stroke
				(width 0.1)
				(type default)
			)
			(layer "F.Fab")
		)
		(fp_line
			(start 0.120396 0.2794)
			(end -0.12065 0.2794)
			(stroke
				(width 0.1)
				(type default)
			)
			(layer "F.Fab")
		)
		(fp_line
			(start -0.12065 -0.2794)
			(end 0.12065 -0.2794)
			(stroke
				(width 0.1)
				(type default)
			)
			(layer "F.Fab")
		)
		(fp_line
			(start 0.12065 -0.2794)
			(end 0.12065 -0.3048)
			(stroke
				(width 0.1)
				(type default)
			)
			(layer "F.Fab")
		)
		(fp_line
			(start 0.12065 -0.3048)
			(end 0.67945 -0.3048)
			(stroke
				(width 0.1)
				(type default)
			)
			(layer "F.Fab")
		)
		(fp_line
			(start 0.67945 -0.3048)
			(end 0.67945 0.3048)
			(stroke
				(width 0.1)
				(type default)
			)
			(layer "F.Fab")
		)
		(fp_line
			(start -0.67945 -0.305054)
			(end -0.12065 -0.305054)
			(stroke
				(width 0.1)
				(type default)
			)
			(layer "F.Fab")
		)
		(fp_line
			(start -0.12065 -0.305054)
			(end -0.12065 -0.2794)
			(stroke
				(width 0.1)
				(type default)
			)
			(layer "F.Fab")
		)
		(pad "1" smd circle
			(at -0.40005 0 270)
			(size 0 0)
			(layers "F.Cu" "F.Mask" "F.Paste")
			(net "GPU_FPGA_RST_R1_BUF_N")
		)
		(pad "2" smd circle
			(at 0.40005 0 270)
			(size 0 0)
			(layers "F.Cu" "F.Mask" "F.Paste")
			(net "GPU_FPGA_RST_R_BUF_N")
		)
	)
	(footprint ""
		(layer "F.Cu")
		(at 21.176996 -99.413314 180)
		(property "Reference" "R3657"
			(at 0 0 180)
			(layer "F.SilkS")
			(hide yes)
			(effects
				(font
					(size 1.27 1.27)
				)
			)
		)
		(property "Value" ""
			(at 0 0 180)
			(layer "F.Fab")
			(effects
				(font
					(size 1.27 1.27)
				)
			)
		)
		(duplicate_pad_numbers_are_jumpers no)
		(fp_line
			(start 0.7874 0.4064)
			(end -0.7874 0.4064)
			(stroke
				(width 0.1524)
				(type default)
			)
			(layer "F.SilkS")
		)
		(fp_line
			(start 0.7874 -0.4064)
			(end 0.7874 0.4064)
			(stroke
				(width 0.1524)
				(type default)
			)
			(layer "F.SilkS")
		)
		(fp_line
			(start -0.7874 0.4064)
			(end -0.7874 -0.4064)
			(stroke
				(width 0.1524)
				(type default)
			)
			(layer "F.SilkS")
		)
		(fp_line
			(start -0.7874 -0.4064)
			(end 0.7874 -0.4064)
			(stroke
				(width 0.1524)
				(type default)
			)
			(layer "F.SilkS")
		)
		(fp_line
			(start 0.67945 0.3048)
			(end 0.120396 0.3048)
			(stroke
				(width 0.1)
				(type default)
			)
			(layer "F.Fab")
		)
		(fp_line
			(start 0.67945 -0.3048)
			(end 0.67945 0.3048)
			(stroke
				(width 0.1)
				(type default)
			)
			(layer "F.Fab")
		)
		(fp_line
			(start 0.12065 -0.2794)
			(end 0.12065 -0.3048)
			(stroke
				(width 0.1)
				(type default)
			)
			(layer "F.Fab")
		)
		(fp_line
			(start 0.12065 -0.3048)
			(end 0.67945 -0.3048)
			(stroke
				(width 0.1)
				(type default)
			)
			(layer "F.Fab")
		)
		(fp_line
			(start 0.120396 0.3048)
			(end 0.120396 0.2794)
			(stroke
				(width 0.1)
				(type default)
			)
			(layer "F.Fab")
		)
		(fp_line
			(start 0.120396 0.2794)
			(end -0.12065 0.2794)
			(stroke
				(width 0.1)
				(type default)
			)
			(layer "F.Fab")
		)
		(fp_line
			(start -0.12065 0.3048)
			(end -0.67945 0.3048)
			(stroke
				(width 0.1)
				(type default)
			)
			(layer "F.Fab")
		)
		(fp_line
			(start -0.12065 0.2794)
			(end -0.12065 0.3048)
			(stroke
				(width 0.1)
				(type default)
			)
			(layer "F.Fab")
		)
		(fp_line
			(start -0.12065 -0.2794)
			(end 0.12065 -0.2794)
			(stroke
				(width 0.1)
				(type default)
			)
			(layer "F.Fab")
		)
		(fp_line
			(start -0.12065 -0.305054)
			(end -0.12065 -0.2794)
			(stroke
				(width 0.1)
				(type default)
			)
			(layer "F.Fab")
		)
		(fp_line
			(start -0.67945 0.3048)
			(end -0.67945 -0.305054)
			(stroke
				(width 0.1)
				(type default)
			)
			(layer "F.Fab")
		)
		(fp_line
			(start -0.67945 -0.305054)
			(end -0.12065 -0.305054)
			(stroke
				(width 0.1)
				(type default)
			)
			(layer "F.Fab")
		)
		(pad "1" smd circle
			(at -0.40005 0 180)
			(size 0 0)
			(layers "F.Cu" "F.Mask" "F.Paste")
			(net "P3V3_AUX")
		)
		(pad "2" smd circle
			(at 0.40005 0 180)
			(size 0 0)
			(layers "F.Cu" "F.Mask" "F.Paste")
			(net "USB_HUB_OVCUR2")
		)
	)
	(footprint ""
		(layer "F.Cu")
		(at 103.413814 -37.6682)
		(property "Reference" "R6327"
			(at 0 0 0)
			(layer "F.SilkS")
			(hide yes)
			(effects
				(font
					(size 1.27 1.27)
				)
			)
		)
		(property "Value" ""
			(at 0 0 0)
			(layer "F.Fab")
			(effects
				(font
					(size 1.27 1.27)
				)
			)
		)
		(duplicate_pad_numbers_are_jumpers no)
		(fp_line
			(start -0.7874 -0.4064)
			(end 0.7874 -0.4064)
			(stroke
				(width 0.1524)
				(type default)
			)
			(layer "F.SilkS")
		)
		(fp_line
			(start -0.7874 0.4064)
			(end -0.7874 -0.4064)
			(stroke
				(width 0.1524)
				(type default)
			)
			(layer "F.SilkS")
		)
		(fp_line
			(start 0.7874 -0.4064)
			(end 0.7874 0.4064)
			(stroke
				(width 0.1524)
				(type default)
			)
			(layer "F.SilkS")
		)
		(fp_line
			(start 0.7874 0.4064)
			(end -0.7874 0.4064)
			(stroke
				(width 0.1524)
				(type default)
			)
			(layer "F.SilkS")
		)
		(fp_line
			(start -0.67945 -0.305054)
			(end -0.12065 -0.305054)
			(stroke
				(width 0.1)
				(type default)
			)
			(layer "F.Fab")
		)
		(fp_line
			(start -0.67945 0.3048)
			(end -0.67945 -0.305054)
			(stroke
				(width 0.1)
				(type default)
			)
			(layer "F.Fab")
		)
		(fp_line
			(start -0.12065 -0.305054)
			(end -0.12065 -0.2794)
			(stroke
				(width 0.1)
				(type default)
			)
			(layer "F.Fab")
		)
		(fp_line
			(start -0.12065 -0.2794)
			(end 0.12065 -0.2794)
			(stroke
				(width 0.1)
				(type default)
			)
			(layer "F.Fab")
		)
		(fp_line
			(start -0.12065 0.2794)
			(end -0.12065 0.3048)
			(stroke
				(width 0.1)
				(type default)
			)
			(layer "F.Fab")
		)
		(fp_line
			(start -0.12065 0.3048)
			(end -0.67945 0.3048)
			(stroke
				(width 0.1)
				(type default)
			)
			(layer "F.Fab")
		)
		(fp_line
			(start 0.120396 0.2794)
			(end -0.12065 0.2794)
			(stroke
				(width 0.1)
				(type default)
			)
			(layer "F.Fab")
		)
		(fp_line
			(start 0.120396 0.3048)
			(end 0.120396 0.2794)
			(stroke
				(width 0.1)
				(type default)
			)
			(layer "F.Fab")
		)
		(fp_line
			(start 0.12065 -0.3048)
			(end 0.67945 -0.3048)
			(stroke
				(width 0.1)
				(type default)
			)
			(layer "F.Fab")
		)
		(fp_line
			(start 0.12065 -0.2794)
			(end 0.12065 -0.3048)
			(stroke
				(width 0.1)
				(type default)
			)
			(layer "F.Fab")
		)
		(fp_line
			(start 0.67945 -0.3048)
			(end 0.67945 0.3048)
			(stroke
				(width 0.1)
				(type default)
			)
			(layer "F.Fab")
		)
		(fp_line
			(start 0.67945 0.3048)
			(end 0.120396 0.3048)
			(stroke
				(width 0.1)
				(type default)
			)
			(layer "F.Fab")
		)
		(pad "1" smd circle
			(at -0.40005 0)
			(size 0 0)
			(layers "F.Cu" "F.Mask" "F.Paste")
			(net "P3V3_AUX")
		)
		(pad "2" smd circle
			(at 0.40005 0)
			(size 0 0)
			(layers "F.Cu" "F.Mask" "F.Paste")
			(net "USB_HUB2_MRP_PROG_FUNC6")
		)
	)
)
